(kicad_pcb
	(version 20260206)
	(generator "pcbnew")
	(generator_version "10.0")
	(general
		(thickness 1.6)
		(legacy_teardrops no)
	)
	(paper "A4")
	(title_block
		(title "01162023_DA0F0TEBIF0_F0T_Expander_BD_F_brd_V02_OCP.brd")
		(comment 1 "Grand Teton / footprints 2148-2153 of 9728")
	)
	(layers
		(0 "F.Cu" signal "TOP")
		(4 "In1.Cu" signal "GND")
		(6 "In2.Cu" signal "VCC")
		(8 "In3.Cu" signal "VCC1")
		(10 "In4.Cu" signal "GND1")
		(12 "In5.Cu" signal "IN1")
		(14 "In6.Cu" signal "GND2")
		(16 "In7.Cu" signal "IN2")
		(18 "In8.Cu" signal "GND3")
		(20 "In9.Cu" signal "IN3")
		(22 "In10.Cu" signal "GND4")
		(24 "In11.Cu" signal "IN4")
		(26 "In12.Cu" signal "GND5")
		(28 "In13.Cu" signal "IN5")
		(30 "In14.Cu" signal "GND6")
		(32 "In15.Cu" signal "IN6")
		(34 "In16.Cu" signal "GND7")
		(2 "B.Cu" signal "BOTTOM")
		(9 "F.Adhes" user "F.Adhesive")
		(11 "B.Adhes" user "B.Adhesive")
		(13 "F.Paste" user "Package Geometry/Pastemask Top")
		(15 "B.Paste" user "Package Geometry/Pastemask Bottom")
		(5 "F.SilkS" user "Ref Des/Silkscreen Top")
		(7 "B.SilkS" user "Ref Des/Silkscreen Bottom")
		(1 "F.Mask" user "Board Geometry/Soldermask Top")
		(3 "B.Mask" user "Board Geometry/Soldermask Bottom")
		(17 "Dwgs.User" user "User.Drawings")
		(19 "Cmts.User" user "User.Comments")
		(21 "Eco1.User" user "User.Eco1")
		(23 "Eco2.User" user "User.Eco2")
		(25 "Edge.Cuts" user "Board Geometry/Outline")
		(27 "Margin" user)
		(31 "F.CrtYd" user "Package Geometry/Place Bound Top")
		(29 "B.CrtYd" user "Package Geometry/Place Bound Bottom")
		(35 "F.Fab" user "Ref Des/Assembly Top")
		(33 "B.Fab" user "Ref Des/Assembly Bottom")
	)
	(footprint ""
		(layer "F.Cu")
		(at 150.21052 -63.652146 180)
		(property "Reference" "R5977"
			(at 0 0 180)
			(layer "F.SilkS")
			(hide yes)
			(effects
				(font
					(size 1.27 1.27)
				)
			)
		)
		(property "Value" ""
			(at 0 0 180)
			(layer "F.Fab")
			(effects
				(font
					(size 1.27 1.27)
				)
			)
		)
		(duplicate_pad_numbers_are_jumpers no)
		(fp_line
			(start 0.7874 0.4064)
			(end -0.7874 0.4064)
			(stroke
				(width 0.1524)
				(type default)
			)
			(layer "F.SilkS")
		)
		(fp_line
			(start 0.7874 -0.4064)
			(end 0.7874 0.4064)
			(stroke
				(width 0.1524)
				(type default)
			)
			(layer "F.SilkS")
		)
		(fp_line
			(start -0.7874 0.4064)
			(end -0.7874 -0.4064)
			(stroke
				(width 0.1524)
				(type default)
			)
			(layer "F.SilkS")
		)
		(fp_line
			(start -0.7874 -0.4064)
			(end 0.7874 -0.4064)
			(stroke
				(width 0.1524)
				(type default)
			)
			(layer "F.SilkS")
		)
		(fp_line
			(start 0.67945 0.3048)
			(end 0.120396 0.3048)
			(stroke
				(width 0.1)
				(type default)
			)
			(layer "F.Fab")
		)
		(fp_line
			(start 0.67945 -0.3048)
			(end 0.67945 0.3048)
			(stroke
				(width 0.1)
				(type default)
			)
			(layer "F.Fab")
		)
		(fp_line
			(start 0.12065 -0.2794)
			(end 0.12065 -0.3048)
			(stroke
				(width 0.1)
				(type default)
			)
			(layer "F.Fab")
		)
		(fp_line
			(start 0.12065 -0.3048)
			(end 0.67945 -0.3048)
			(stroke
				(width 0.1)
				(type default)
			)
			(layer "F.Fab")
		)
		(fp_line
			(start 0.120396 0.3048)
			(end 0.120396 0.2794)
			(stroke
				(width 0.1)
				(type default)
			)
			(layer "F.Fab")
		)
		(fp_line
			(start 0.120396 0.2794)
			(end -0.12065 0.2794)
			(stroke
				(width 0.1)
				(type default)
			)
			(layer "F.Fab")
		)
		(fp_line
			(start -0.12065 0.3048)
			(end -0.67945 0.3048)
			(stroke
				(width 0.1)
				(type default)
			)
			(layer "F.Fab")
		)
		(fp_line
			(start -0.12065 0.2794)
			(end -0.12065 0.3048)
			(stroke
				(width 0.1)
				(type default)
			)
			(layer "F.Fab")
		)
		(fp_line
			(start -0.12065 -0.2794)
			(end 0.12065 -0.2794)
			(stroke
				(width 0.1)
				(type default)
			)
			(layer "F.Fab")
		)
		(fp_line
			(start -0.12065 -0.305054)
			(end -0.12065 -0.2794)
			(stroke
				(width 0.1)
				(type default)
			)
			(layer "F.Fab")
		)
		(fp_line
			(start -0.67945 0.3048)
			(end -0.67945 -0.305054)
			(stroke
				(width 0.1)
				(type default)
			)
			(layer "F.Fab")
		)
		(fp_line
			(start -0.67945 -0.305054)
			(end -0.12065 -0.305054)
			(stroke
				(width 0.1)
				(type default)
			)
			(layer "F.Fab")
		)
		(pad "1" smd circle
			(at -0.40005 0 180)
			(size 0 0)
			(layers "F.Cu" "F.Mask" "F.Paste")
			(net "P5V_AUX")
		)
		(pad "2" smd circle
			(at 0.40005 0 180)
			(size 0 0)
			(layers "F.Cu" "F.Mask" "F.Paste")
			(net "P12V_SSD5_PG_G2")
		)
	)
	(footprint ""
		(layer "F.Cu")
		(at 206.297276 -309.0418 135)
		(property "Reference" "R1316"
			(at 0 0 135)
			(layer "F.SilkS")
			(hide yes)
			(effects
				(font
					(size 1.27 1.27)
				)
			)
		)
		(property "Value" ""
			(at 0 0 135)
			(layer "F.Fab")
			(effects
				(font
					(size 1.27 1.27)
				)
			)
		)
		(duplicate_pad_numbers_are_jumpers no)
		(fp_line
			(start 0.787389 -0.406267)
			(end 0.787389 0.406267)
			(stroke
				(width 0.1524)
				(type default)
			)
			(layer "F.SilkS")
		)
		(fp_line
			(start 0.787389 0.406267)
			(end -0.787389 0.406267)
			(stroke
				(width 0.1524)
				(type default)
			)
			(layer "F.SilkS")
		)
		(fp_line
			(start -0.787389 -0.406267)
			(end 0.787389 -0.406267)
			(stroke
				(width 0.1524)
				(type default)
			)
			(layer "F.SilkS")
		)
		(fp_line
			(start -0.787389 0.406267)
			(end -0.787389 -0.406267)
			(stroke
				(width 0.1524)
				(type default)
			)
			(layer "F.SilkS")
		)
		(fp_line
			(start 0.679446 -0.30479)
			(end 0.679446 0.30479)
			(stroke
				(width 0.1)
				(type default)
			)
			(layer "F.Fab")
		)
		(fp_line
			(start 0.120515 -0.30479)
			(end 0.679446 -0.30479)
			(stroke
				(width 0.1)
				(type default)
			)
			(layer "F.Fab")
		)
		(fp_line
			(start 0.120695 -0.279466)
			(end 0.120515 -0.30479)
			(stroke
				(width 0.1)
				(type default)
			)
			(layer "F.Fab")
		)
		(fp_line
			(start 0.679446 0.30479)
			(end 0.120515 0.30479)
			(stroke
				(width 0.1)
				(type default)
			)
			(layer "F.Fab")
		)
		(fp_line
			(start -0.120695 -0.304969)
			(end -0.120695 -0.279466)
			(stroke
				(width 0.1)
				(type default)
			)
			(layer "F.Fab")
		)
		(fp_line
			(start -0.120695 -0.279466)
			(end 0.120695 -0.279466)
			(stroke
				(width 0.1)
				(type default)
			)
			(layer "F.Fab")
		)
		(fp_line
			(start 0.120335 0.279466)
			(end -0.120695 0.279466)
			(stroke
				(width 0.1)
				(type default)
			)
			(layer "F.Fab")
		)
		(fp_line
			(start 0.120515 0.30479)
			(end 0.120335 0.279466)
			(stroke
				(width 0.1)
				(type default)
			)
			(layer "F.Fab")
		)
		(fp_line
			(start -0.679446 -0.305149)
			(end -0.120695 -0.304969)
			(stroke
				(width 0.1)
				(type default)
			)
			(layer "F.Fab")
		)
		(fp_line
			(start -0.120695 0.279466)
			(end -0.120515 0.30479)
			(stroke
				(width 0.1)
				(type default)
			)
			(layer "F.Fab")
		)
		(fp_line
			(start -0.120515 0.30479)
			(end -0.679446 0.30479)
			(stroke
				(width 0.1)
				(type default)
			)
			(layer "F.Fab")
		)
		(fp_line
			(start -0.679446 0.30479)
			(end -0.679446 -0.305149)
			(stroke
				(width 0.1)
				(type default)
			)
			(layer "F.Fab")
		)
		(pad "1" smd circle
			(at -0.40005 0 135)
			(size 0 0)
			(layers "F.Cu" "F.Mask" "F.Paste")
			(net "GND")
		)
		(pad "2" smd circle
			(at 0.40005 0 135)
			(size 0 0)
			(layers "F.Cu" "F.Mask" "F.Paste")
			(net "PEX1_SPARE2")
		)
	)
	(footprint ""
		(layer "F.Cu")
		(at 136.445244 -93.528642 180)
		(property "Reference" "R1586"
			(at 0 0 180)
			(layer "F.SilkS")
			(hide yes)
			(effects
				(font
					(size 1.27 1.27)
				)
			)
		)
		(property "Value" ""
			(at 0 0 180)
			(layer "F.Fab")
			(effects
				(font
					(size 1.27 1.27)
				)
			)
		)
		(duplicate_pad_numbers_are_jumpers no)
		(fp_line
			(start 0.7874 0.4064)
			(end -0.7874 0.4064)
			(stroke
				(width 0.1524)
				(type default)
			)
			(layer "F.SilkS")
		)
		(fp_line
			(start 0.7874 -0.4064)
			(end 0.7874 0.4064)
			(stroke
				(width 0.1524)
				(type default)
			)
			(layer "F.SilkS")
		)
		(fp_line
			(start -0.7874 0.4064)
			(end -0.7874 -0.4064)
			(stroke
				(width 0.1524)
				(type default)
			)
			(layer "F.SilkS")
		)
		(fp_line
			(start -0.7874 -0.4064)
			(end 0.7874 -0.4064)
			(stroke
				(width 0.1524)
				(type default)
			)
			(layer "F.SilkS")
		)
		(fp_line
			(start 0.67945 0.3048)
			(end 0.120396 0.3048)
			(stroke
				(width 0.1)
				(type default)
			)
			(layer "F.Fab")
		)
		(fp_line
			(start 0.67945 -0.3048)
			(end 0.67945 0.3048)
			(stroke
				(width 0.1)
				(type default)
			)
			(layer "F.Fab")
		)
		(fp_line
			(start 0.12065 -0.2794)
			(end 0.12065 -0.3048)
			(stroke
				(width 0.1)
				(type default)
			)
			(layer "F.Fab")
		)
		(fp_line
			(start 0.12065 -0.3048)
			(end 0.67945 -0.3048)
			(stroke
				(width 0.1)
				(type default)
			)
			(layer "F.Fab")
		)
		(fp_line
			(start 0.120396 0.3048)
			(end 0.120396 0.2794)
			(stroke
				(width 0.1)
				(type default)
			)
			(layer "F.Fab")
		)
		(fp_line
			(start 0.120396 0.2794)
			(end -0.12065 0.2794)
			(stroke
				(width 0.1)
				(type default)
			)
			(layer "F.Fab")
		)
		(fp_line
			(start -0.12065 0.3048)
			(end -0.67945 0.3048)
			(stroke
				(width 0.1)
				(type default)
			)
			(layer "F.Fab")
		)
		(fp_line
			(start -0.12065 0.2794)
			(end -0.12065 0.3048)
			(stroke
				(width 0.1)
				(type default)
			)
			(layer "F.Fab")
		)
		(fp_line
			(start -0.12065 -0.2794)
			(end 0.12065 -0.2794)
			(stroke
				(width 0.1)
				(type default)
			)
			(layer "F.Fab")
		)
		(fp_line
			(start -0.12065 -0.305054)
			(end -0.12065 -0.2794)
			(stroke
				(width 0.1)
				(type default)
			)
			(layer "F.Fab")
		)
		(fp_line
			(start -0.67945 0.3048)
			(end -0.67945 -0.305054)
			(stroke
				(width 0.1)
				(type default)
			)
			(layer "F.Fab")
		)
		(fp_line
			(start -0.67945 -0.305054)
			(end -0.12065 -0.305054)
			(stroke
				(width 0.1)
				(type default)
			)
			(layer "F.Fab")
		)
		(pad "1" smd circle
			(at -0.40005 0 180)
			(size 0 0)
			(layers "F.Cu" "F.Mask" "F.Paste")
			(net "SMB_BIC_I2C9_MUX0_SSD6_R_SCL")
		)
		(pad "2" smd circle
			(at 0.40005 0 180)
			(size 0 0)
			(layers "F.Cu" "F.Mask" "F.Paste")
			(net "SMB_BIC_I2C9_MUX0_SSD6_SCL")
		)
	)
	(footprint ""
		(layer "F.Cu")
		(at 153.347928 -102.009702)
		(property "Reference" "C273"
			(at 0 0 0)
			(layer "F.SilkS")
			(hide yes)
			(effects
				(font
					(size 1.27 1.27)
				)
			)
		)
		(property "Value" ""
			(at 0 0 0)
			(layer "F.Fab")
			(effects
				(font
					(size 1.27 1.27)
				)
			)
		)
		(duplicate_pad_numbers_are_jumpers no)
		(fp_line
			(start -0.299974 -0.150114)
			(end 0.299974 -0.150114)
			(stroke
				(width 0.1)
				(type default)
			)
			(layer "F.Fab")
		)
		(fp_line
			(start -0.299974 0.150114)
			(end -0.299974 -0.150114)
			(stroke
				(width 0.1)
				(type default)
			)
			(layer "F.Fab")
		)
		(fp_line
			(start 0.299974 -0.150114)
			(end 0.299974 0.150114)
			(stroke
				(width 0.1)
				(type default)
			)
			(layer "F.Fab")
		)
		(fp_line
			(start 0.299974 0.150114)
			(end -0.299974 0.150114)
			(stroke
				(width 0.1)
				(type default)
			)
			(layer "F.Fab")
		)
		(pad "1" smd rect
			(at -0.2667 0)
			(size 0.3048 0.381)
			(layers "F.Cu" "F.Mask" "F.Paste")
			(net "P5E_PEX1_STN1_TX_DP<17>")
		)
		(pad "2" smd rect
			(at 0.2667 0)
			(size 0.3048 0.381)
			(layers "F.Cu" "F.Mask" "F.Paste")
			(net "P5E_PEX1_STN1_TX_C_DP<17>")
		)
	)
	(footprint ""
		(layer "F.Cu")
		(at 322.13296 -311.946544 135)
		(property "Reference" "R1369"
			(at 0 0 135)
			(layer "F.SilkS")
			(hide yes)
			(effects
				(font
					(size 1.27 1.27)
				)
			)
		)
		(property "Value" ""
			(at 0 0 135)
			(layer "F.Fab")
			(effects
				(font
					(size 1.27 1.27)
				)
			)
		)
		(duplicate_pad_numbers_are_jumpers no)
		(fp_line
			(start 0.787389 -0.406267)
			(end 0.787389 0.406267)
			(stroke
				(width 0.1524)
				(type default)
			)
			(layer "F.SilkS")
		)
		(fp_line
			(start 0.787389 0.406267)
			(end -0.787389 0.406267)
			(stroke
				(width 0.1524)
				(type default)
			)
			(layer "F.SilkS")
		)
		(fp_line
			(start -0.787389 -0.406267)
			(end 0.787389 -0.406267)
			(stroke
				(width 0.1524)
				(type default)
			)
			(layer "F.SilkS")
		)
		(fp_line
			(start -0.787389 0.406267)
			(end -0.787389 -0.406267)
			(stroke
				(width 0.1524)
				(type default)
			)
			(layer "F.SilkS")
		)
		(fp_line
			(start 0.679446 -0.30479)
			(end 0.679446 0.30479)
			(stroke
				(width 0.1)
				(type default)
			)
			(layer "F.Fab")
		)
		(fp_line
			(start 0.120515 -0.30479)
			(end 0.679446 -0.30479)
			(stroke
				(width 0.1)
				(type default)
			)
			(layer "F.Fab")
		)
		(fp_line
			(start 0.120695 -0.279466)
			(end 0.120515 -0.30479)
			(stroke
				(width 0.1)
				(type default)
			)
			(layer "F.Fab")
		)
		(fp_line
			(start 0.679446 0.30479)
			(end 0.120515 0.30479)
			(stroke
				(width 0.1)
				(type default)
			)
			(layer "F.Fab")
		)
		(fp_line
			(start -0.120695 -0.304969)
			(end -0.120695 -0.279466)
			(stroke
				(width 0.1)
				(type default)
			)
			(layer "F.Fab")
		)
		(fp_line
			(start -0.120695 -0.279466)
			(end 0.120695 -0.279466)
			(stroke
				(width 0.1)
				(type default)
			)
			(layer "F.Fab")
		)
		(fp_line
			(start 0.120335 0.279466)
			(end -0.120695 0.279466)
			(stroke
				(width 0.1)
				(type default)
			)
			(layer "F.Fab")
		)
		(fp_line
			(start 0.120515 0.30479)
			(end 0.120335 0.279466)
			(stroke
				(width 0.1)
				(type default)
			)
			(layer "F.Fab")
		)
		(fp_line
			(start -0.679446 -0.305149)
			(end -0.120695 -0.304969)
			(stroke
				(width 0.1)
				(type default)
			)
			(layer "F.Fab")
		)
		(fp_line
			(start -0.120695 0.279466)
			(end -0.120515 0.30479)
			(stroke
				(width 0.1)
				(type default)
			)
			(layer "F.Fab")
		)
		(fp_line
			(start -0.120515 0.30479)
			(end -0.679446 0.30479)
			(stroke
				(width 0.1)
				(type default)
			)
			(layer "F.Fab")
		)
		(fp_line
			(start -0.679446 0.30479)
			(end -0.679446 -0.305149)
			(stroke
				(width 0.1)
				(type default)
			)
			(layer "F.Fab")
		)
		(pad "1" smd circle
			(at -0.40005 0 135)
			(size 0 0)
			(layers "F.Cu" "F.Mask" "F.Paste")
			(net "PEX2_SPARE5")
		)
		(pad "2" smd circle
			(at 0.40005 0 135)
			(size 0 0)
			(layers "F.Cu" "F.Mask" "F.Paste")
			(net "P1V8_PEX")
		)
	)
	(footprint ""
		(layer "F.Cu")
		(at 268.53515 -81.087722 180)
		(property "Reference" "R1074"
			(at 0 0 180)
			(layer "F.SilkS")
			(hide yes)
			(effects
				(font
					(size 1.27 1.27)
				)
			)
		)
		(property "Value" ""
			(at 0 0 180)
			(layer "F.Fab")
			(effects
				(font
					(size 1.27 1.27)
				)
			)
		)
		(duplicate_pad_numbers_are_jumpers no)
		(fp_line
			(start -0.7874 -0.4064)
			(end 0.7874 -0.4064)
			(stroke
				(width 0.1524)
				(type default)
			)
			(layer "F.SilkS")
		)
		(fp_line
			(start 0.67945 0.3048)
			(end 0.120396 0.3048)
			(stroke
				(width 0.1)
				(type default)
			)
			(layer "F.Fab")
		)
		(fp_line
			(start 0.67945 -0.3048)
			(end 0.67945 0.3048)
			(stroke
				(width 0.1)
				(type default)
			)
			(layer "F.Fab")
		)
		(fp_line
			(start 0.12065 -0.2794)
			(end 0.12065 -0.3048)
			(stroke
				(width 0.1)
				(type default)
			)
			(layer "F.Fab")
		)
		(fp_line
			(start 0.12065 -0.3048)
			(end 0.67945 -0.3048)
			(stroke
				(width 0.1)
				(type default)
			)
			(layer "F.Fab")
		)
		(fp_line
			(start 0.120396 0.3048)
			(end 0.120396 0.2794)
			(stroke
				(width 0.1)
				(type default)
			)
			(layer "F.Fab")
		)
		(fp_line
			(start 0.120396 0.2794)
			(end -0.12065 0.2794)
			(stroke
				(width 0.1)
				(type default)
			)
			(layer "F.Fab")
		)
		(fp_line
			(start -0.12065 0.3048)
			(end -0.67945 0.3048)
			(stroke
				(width 0.1)
				(type default)
			)
			(layer "F.Fab")
		)
		(fp_line
			(start -0.12065 0.2794)
			(end -0.12065 0.3048)
			(stroke
				(width 0.1)
				(type default)
			)
			(layer "F.Fab")
		)
		(fp_line
			(start -0.12065 -0.2794)
			(end 0.12065 -0.2794)
			(stroke
				(width 0.1)
				(type default)
			)
			(layer "F.Fab")
		)
		(fp_line
			(start -0.12065 -0.305054)
			(end -0.12065 -0.2794)
			(stroke
				(width 0.1)
				(type default)
			)
			(layer "F.Fab")
		)
		(fp_line
			(start -0.67945 0.3048)
			(end -0.67945 -0.305054)
			(stroke
				(width 0.1)
				(type default)
			)
			(layer "F.Fab")
		)
		(fp_line
			(start -0.67945 -0.305054)
			(end -0.12065 -0.305054)
			(stroke
				(width 0.1)
				(type default)
			)
			(layer "F.Fab")
		)
		(pad "1" smd circle
			(at -0.40005 0 180)
			(size 0 0)
			(layers "F.Cu" "F.Mask" "F.Paste")
			(net "CLK_100M_CK440Q_1_DB800ZL_R_DN")
		)
		(pad "2" smd circle
			(at 0.40005 0 180)
			(size 0 0)
			(layers "F.Cu" "F.Mask" "F.Paste")
			(net "CLK_100M_CK440Q_1_DB800ZL_DN")
		)
	)
)
